# SCM (Grand Teton) — schematic netlist excerpt (pin names and nets, part order shuffled) for the footprints in the layout excerpt that follows; sources: Cadence DE-HDL packaged netlist, KiCad conversion of 12092022_DA0F0TMDCD0_F0T_Management_Board_D_brd_V3_OCP.brd

C311  Q_CAP  0.1UF 25V 10% X7R  pkg 0402  page 15 : A = P1V0_SENSOR ; B = GND
R387  Q_RES  100K 1% CHIP  pkg 0402LF  page 12 : A = GND ; B = DP_BMC_HPD_3V3_BUF

(kicad_pcb
	(version 20260206)
	(generator "pcbnew")
	(generator_version "10.0")
	(general
		(thickness 1.6)
		(legacy_teardrops no)
	)
	(paper "A4")
	(title_block
		(title "12092022_DA0F0TMDCD0_F0T_Management_Board_D_brd_V3_OCP.brd")
		(comment 1 "Grand Teton / footprints 763-764 of 1440")
	)
	(layers
		(0 "F.Cu" signal "TOP")
		(4 "In1.Cu" signal "GND")
		(6 "In2.Cu" signal "IN1")
		(8 "In3.Cu" signal "GND1")
		(10 "In4.Cu" signal "IN2")
		(12 "In5.Cu" signal "VCC")
		(14 "In6.Cu" signal "VCC1")
		(16 "In7.Cu" signal "IN3")
		(18 "In8.Cu" signal "GND2")
		(20 "In9.Cu" signal "IN4")
		(22 "In10.Cu" signal "GND3")
		(2 "B.Cu" signal "BOTTOM")
		(9 "F.Adhes" user "F.Adhesive")
		(11 "B.Adhes" user "B.Adhesive")
		(13 "F.Paste" user "Package Geometry/Pastemask Top")
		(15 "B.Paste" user "Package Geometry/Pastemask Bottom")
		(5 "F.SilkS" user "Ref Des/Silkscreen Top")
		(7 "B.SilkS" user "Ref Des/Silkscreen Bottom")
		(1 "F.Mask" user "Board Geometry/Soldermask Top")
		(3 "B.Mask" user "Board Geometry/Soldermask Bottom")
		(17 "Dwgs.User" user "User.Drawings")
		(19 "Cmts.User" user "User.Comments")
		(21 "Eco1.User" user "User.Eco1")
		(23 "Eco2.User" user "User.Eco2")
		(25 "Edge.Cuts" user "Board Geometry/Outline")
		(27 "Margin" user)
		(31 "F.CrtYd" user "Package Geometry/Place Bound Top")
		(29 "B.CrtYd" user "Package Geometry/Place Bound Bottom")
		(35 "F.Fab" user "Ref Des/Assembly Top")
		(33 "B.Fab" user "Ref Des/Assembly Bottom")
	)
	(footprint ""
		(layer "B.Cu")
		(at 49.3014 -66.72072 90)
		(property "Reference" "C311"
			(at 0 0 90)
			(layer "B.SilkS")
			(hide yes)
			(effects
				(font
					(size 1.27 1.27)
				)
				(justify mirror)
			)
		)
		(property "Value" ""
			(at 0 0 90)
			(layer "B.Fab")
			(effects
				(font
					(size 1.27 1.27)
				)
				(justify mirror)
			)
		)
		(duplicate_pad_numbers_are_jumpers no)
		(fp_line
			(start 0.7874 -0.4064)
			(end -0.7874 -0.4064)
			(stroke
				(width 0.1524)
				(type default)
			)
			(layer "B.SilkS")
		)
		(fp_line
			(start -0.7874 -0.4064)
			(end -0.7874 0.4064)
			(stroke
				(width 0.1524)
				(type default)
			)
			(layer "B.SilkS")
		)
		(fp_line
			(start 0.7874 0.4064)
			(end 0.7874 -0.4064)
			(stroke
				(width 0.1524)
				(type default)
			)
			(layer "B.SilkS")
		)
		(fp_line
			(start -0.7874 0.4064)
			(end 0.7874 0.4064)
			(stroke
				(width 0.1524)
				(type default)
			)
			(layer "B.SilkS")
		)
		(fp_line
			(start 0.67945 -0.305054)
			(end 0.12065 -0.305054)
			(stroke
				(width 0.1)
				(type default)
			)
			(layer "B.Fab")
		)
		(fp_line
			(start 0.12065 -0.305054)
			(end 0.12065 -0.2794)
			(stroke
				(width 0.1)
				(type default)
			)
			(layer "B.Fab")
		)
		(fp_line
			(start -0.12065 -0.3048)
			(end -0.67945 -0.3048)
			(stroke
				(width 0.1)
				(type default)
			)
			(layer "B.Fab")
		)
		(fp_line
			(start -0.67945 -0.3048)
			(end -0.67945 0.3048)
			(stroke
				(width 0.1)
				(type default)
			)
			(layer "B.Fab")
		)
		(fp_line
			(start 0.12065 -0.2794)
			(end -0.12065 -0.2794)
			(stroke
				(width 0.1)
				(type default)
			)
			(layer "B.Fab")
		)
		(fp_line
			(start -0.12065 -0.2794)
			(end -0.12065 -0.3048)
			(stroke
				(width 0.1)
				(type default)
			)
			(layer "B.Fab")
		)
		(fp_line
			(start 0.12065 0.2794)
			(end 0.12065 0.3048)
			(stroke
				(width 0.1)
				(type default)
			)
			(layer "B.Fab")
		)
		(fp_line
			(start -0.120396 0.2794)
			(end 0.12065 0.2794)
			(stroke
				(width 0.1)
				(type default)
			)
			(layer "B.Fab")
		)
		(fp_line
			(start 0.67945 0.3048)
			(end 0.67945 -0.305054)
			(stroke
				(width 0.1)
				(type default)
			)
			(layer "B.Fab")
		)
		(fp_line
			(start 0.12065 0.3048)
			(end 0.67945 0.3048)
			(stroke
				(width 0.1)
				(type default)
			)
			(layer "B.Fab")
		)
		(fp_line
			(start -0.120396 0.3048)
			(end -0.120396 0.2794)
			(stroke
				(width 0.1)
				(type default)
			)
			(layer "B.Fab")
		)
		(fp_line
			(start -0.67945 0.3048)
			(end -0.120396 0.3048)
			(stroke
				(width 0.1)
				(type default)
			)
			(layer "B.Fab")
		)
		(pad "1" smd circle
			(at 0.40005 0 270)
			(size 0 0)
			(layers "B.Cu" "B.Mask" "B.Paste")
			(net "P1V0_SENSOR")
		)
		(pad "2" smd circle
			(at -0.40005 0 270)
			(size 0 0)
			(layers "B.Cu" "B.Mask" "B.Paste")
			(net "GND")
		)
	)
	(footprint ""
		(layer "B.Cu")
		(at 64.794384 -40.322754)
		(property "Reference" "R387"
			(at 0 0 0)
			(layer "B.SilkS")
			(hide yes)
			(effects
				(font
					(size 1.27 1.27)
				)
				(justify mirror)
			)
		)
		(property "Value" ""
			(at 0 0 0)
			(layer "B.Fab")
			(effects
				(font
					(size 1.27 1.27)
				)
				(justify mirror)
			)
		)
		(duplicate_pad_numbers_are_jumpers no)
		(fp_line
			(start -0.7874 -0.4064)
			(end -0.7874 0.4064)
			(stroke
				(width 0.1524)
				(type default)
			)
			(layer "B.SilkS")
		)
		(fp_line
			(start -0.7874 0.4064)
			(end 0.7874 0.4064)
			(stroke
				(width 0.1524)
				(type default)
			)
			(layer "B.SilkS")
		)
		(fp_line
			(start 0.7874 -0.4064)
			(end -0.7874 -0.4064)
			(stroke
				(width 0.1524)
				(type default)
			)
			(layer "B.SilkS")
		)
		(fp_line
			(start 0.7874 0.4064)
			(end 0.7874 -0.4064)
			(stroke
				(width 0.1524)
				(type default)
			)
			(layer "B.SilkS")
		)
		(fp_line
			(start -0.67945 -0.3048)
			(end -0.67945 0.3048)
			(stroke
				(width 0.1)
				(type default)
			)
			(layer "B.Fab")
		)
		(fp_line
			(start -0.67945 0.3048)
			(end -0.120396 0.3048)
			(stroke
				(width 0.1)
				(type default)
			)
			(layer "B.Fab")
		)
		(fp_line
			(start -0.12065 -0.3048)
			(end -0.67945 -0.3048)
			(stroke
				(width 0.1)
				(type default)
			)
			(layer "B.Fab")
		)
		(fp_line
			(start -0.12065 -0.2794)
			(end -0.12065 -0.3048)
			(stroke
				(width 0.1)
				(type default)
			)
			(layer "B.Fab")
		)
		(fp_line
			(start -0.120396 0.2794)
			(end 0.12065 0.2794)
			(stroke
				(width 0.1)
				(type default)
			)
			(layer "B.Fab")
		)
		(fp_line
			(start -0.120396 0.3048)
			(end -0.120396 0.2794)
			(stroke
				(width 0.1)
				(type default)
			)
			(layer "B.Fab")
		)
		(fp_line
			(start 0.12065 -0.305054)
			(end 0.12065 -0.2794)
			(stroke
				(width 0.1)
				(type default)
			)
			(layer "B.Fab")
		)
		(fp_line
			(start 0.12065 -0.2794)
			(end -0.12065 -0.2794)
			(stroke
				(width 0.1)
				(type default)
			)
			(layer "B.Fab")
		)
		(fp_line
			(start 0.12065 0.2794)
			(end 0.12065 0.3048)
			(stroke
				(width 0.1)
				(type default)
			)
			(layer "B.Fab")
		)
		(fp_line
			(start 0.12065 0.3048)
			(end 0.67945 0.3048)
			(stroke
				(width 0.1)
				(type default)
			)
			(layer "B.Fab")
		)
		(fp_line
			(start 0.67945 -0.305054)
			(end 0.12065 -0.305054)
			(stroke
				(width 0.1)
				(type default)
			)
			(layer "B.Fab")
		)
		(fp_line
			(start 0.67945 0.3048)
			(end 0.67945 -0.305054)
			(stroke
				(width 0.1)
				(type default)
			)
			(layer "B.Fab")
		)
		(pad "1" smd circle
			(at 0.40005 0 180)
			(size 0 0)
			(layers "B.Cu" "B.Mask" "B.Paste")
			(net "GND")
		)
		(pad "2" smd circle
			(at -0.40005 0 180)
			(size 0 0)
			(layers "B.Cu" "B.Mask" "B.Paste")
			(net "DP_BMC_HPD_3V3_BUF")
		)
	)
)
